(kicad_pcb
	(version 20260206)
	(generator "pcbnew")
	(generator_version "10.0")
	(general
		(thickness 1.6)
		(legacy_teardrops no)
	)
	(paper "A4")
	(title_block
		(title "01162023_DA0F0TEBIF0_F0T_Expander_BD_F_brd_V02_OCP.brd")
		(comment 1 "Grand Teton / footprints 5155-5161 of 9728")
	)
	(layers
		(0 "F.Cu" signal "TOP")
		(4 "In1.Cu" signal "GND")
		(6 "In2.Cu" signal "VCC")
		(8 "In3.Cu" signal "VCC1")
		(10 "In4.Cu" signal "GND1")
		(12 "In5.Cu" signal "IN1")
		(14 "In6.Cu" signal "GND2")
		(16 "In7.Cu" signal "IN2")
		(18 "In8.Cu" signal "GND3")
		(20 "In9.Cu" signal "IN3")
		(22 "In10.Cu" signal "GND4")
		(24 "In11.Cu" signal "IN4")
		(26 "In12.Cu" signal "GND5")
		(28 "In13.Cu" signal "IN5")
		(30 "In14.Cu" signal "GND6")
		(32 "In15.Cu" signal "IN6")
		(34 "In16.Cu" signal "GND7")
		(2 "B.Cu" signal "BOTTOM")
		(9 "F.Adhes" user "F.Adhesive")
		(11 "B.Adhes" user "B.Adhesive")
		(13 "F.Paste" user "Package Geometry/Pastemask Top")
		(15 "B.Paste" user "Package Geometry/Pastemask Bottom")
		(5 "F.SilkS" user "Ref Des/Silkscreen Top")
		(7 "B.SilkS" user "Ref Des/Silkscreen Bottom")
		(1 "F.Mask" user "Board Geometry/Soldermask Top")
		(3 "B.Mask" user "Board Geometry/Soldermask Bottom")
		(17 "Dwgs.User" user "User.Drawings")
		(19 "Cmts.User" user "User.Comments")
		(21 "Eco1.User" user "User.Eco1")
		(23 "Eco2.User" user "User.Eco2")
		(25 "Edge.Cuts" user "Board Geometry/Outline")
		(27 "Margin" user)
		(31 "F.CrtYd" user "Package Geometry/Place Bound Top")
		(29 "B.CrtYd" user "Package Geometry/Place Bound Bottom")
		(35 "F.Fab" user "Ref Des/Assembly Top")
		(33 "B.Fab" user "Ref Des/Assembly Bottom")
	)
	(footprint ""
		(layer "F.Cu")
		(at 361.944158 -380.63043)
		(property "Reference" "R6710"
			(at 0 0 0)
			(layer "F.SilkS")
			(hide yes)
			(effects
				(font
					(size 1.27 1.27)
				)
			)
		)
		(property "Value" ""
			(at 0 0 0)
			(layer "F.Fab")
			(effects
				(font
					(size 1.27 1.27)
				)
			)
		)
		(duplicate_pad_numbers_are_jumpers no)
		(fp_line
			(start -0.7874 -0.4064)
			(end 0.7874 -0.4064)
			(stroke
				(width 0.1524)
				(type default)
			)
			(layer "F.SilkS")
		)
		(fp_line
			(start -0.7874 0.4064)
			(end -0.7874 -0.4064)
			(stroke
				(width 0.1524)
				(type default)
			)
			(layer "F.SilkS")
		)
		(fp_line
			(start 0.7874 -0.4064)
			(end 0.7874 0.4064)
			(stroke
				(width 0.1524)
				(type default)
			)
			(layer "F.SilkS")
		)
		(fp_line
			(start 0.7874 0.4064)
			(end -0.7874 0.4064)
			(stroke
				(width 0.1524)
				(type default)
			)
			(layer "F.SilkS")
		)
		(fp_line
			(start -0.67945 -0.305054)
			(end -0.12065 -0.305054)
			(stroke
				(width 0.1)
				(type default)
			)
			(layer "F.Fab")
		)
		(fp_line
			(start -0.67945 0.3048)
			(end -0.67945 -0.305054)
			(stroke
				(width 0.1)
				(type default)
			)
			(layer "F.Fab")
		)
		(fp_line
			(start -0.12065 -0.305054)
			(end -0.12065 -0.2794)
			(stroke
				(width 0.1)
				(type default)
			)
			(layer "F.Fab")
		)
		(fp_line
			(start -0.12065 -0.2794)
			(end 0.12065 -0.2794)
			(stroke
				(width 0.1)
				(type default)
			)
			(layer "F.Fab")
		)
		(fp_line
			(start -0.12065 0.2794)
			(end -0.12065 0.3048)
			(stroke
				(width 0.1)
				(type default)
			)
			(layer "F.Fab")
		)
		(fp_line
			(start -0.12065 0.3048)
			(end -0.67945 0.3048)
			(stroke
				(width 0.1)
				(type default)
			)
			(layer "F.Fab")
		)
		(fp_line
			(start 0.120396 0.2794)
			(end -0.12065 0.2794)
			(stroke
				(width 0.1)
				(type default)
			)
			(layer "F.Fab")
		)
		(fp_line
			(start 0.120396 0.3048)
			(end 0.120396 0.2794)
			(stroke
				(width 0.1)
				(type default)
			)
			(layer "F.Fab")
		)
		(fp_line
			(start 0.12065 -0.3048)
			(end 0.67945 -0.3048)
			(stroke
				(width 0.1)
				(type default)
			)
			(layer "F.Fab")
		)
		(fp_line
			(start 0.12065 -0.2794)
			(end 0.12065 -0.3048)
			(stroke
				(width 0.1)
				(type default)
			)
			(layer "F.Fab")
		)
		(fp_line
			(start 0.67945 -0.3048)
			(end 0.67945 0.3048)
			(stroke
				(width 0.1)
				(type default)
			)
			(layer "F.Fab")
		)
		(fp_line
			(start 0.67945 0.3048)
			(end 0.120396 0.3048)
			(stroke
				(width 0.1)
				(type default)
			)
			(layer "F.Fab")
		)
		(pad "1" smd circle
			(at -0.40005 0)
			(size 0 0)
			(layers "F.Cu" "F.Mask" "F.Paste")
			(net "MB_3V3IO_RSVD4_ISO_R")
		)
		(pad "2" smd circle
			(at 0.40005 0)
			(size 0 0)
			(layers "F.Cu" "F.Mask" "F.Paste")
			(net "MB_3V3IO_RSVD4_ISO")
		)
	)
	(footprint ""
		(layer "F.Cu")
		(at 452.543672 -48.93691 180)
		(property "Reference" "R677"
			(at 0 0 180)
			(layer "F.SilkS")
			(hide yes)
			(effects
				(font
					(size 1.27 1.27)
				)
			)
		)
		(property "Value" ""
			(at 0 0 180)
			(layer "F.Fab")
			(effects
				(font
					(size 1.27 1.27)
				)
			)
		)
		(duplicate_pad_numbers_are_jumpers no)
		(fp_line
			(start 0.7874 0.4064)
			(end -0.7874 0.4064)
			(stroke
				(width 0.1524)
				(type default)
			)
			(layer "F.SilkS")
		)
		(fp_line
			(start 0.7874 -0.4064)
			(end 0.7874 0.4064)
			(stroke
				(width 0.1524)
				(type default)
			)
			(layer "F.SilkS")
		)
		(fp_line
			(start -0.7874 0.4064)
			(end -0.7874 -0.4064)
			(stroke
				(width 0.1524)
				(type default)
			)
			(layer "F.SilkS")
		)
		(fp_line
			(start -0.7874 -0.4064)
			(end 0.7874 -0.4064)
			(stroke
				(width 0.1524)
				(type default)
			)
			(layer "F.SilkS")
		)
		(fp_line
			(start 0.67945 0.3048)
			(end 0.120396 0.3048)
			(stroke
				(width 0.1)
				(type default)
			)
			(layer "F.Fab")
		)
		(fp_line
			(start 0.67945 -0.3048)
			(end 0.67945 0.3048)
			(stroke
				(width 0.1)
				(type default)
			)
			(layer "F.Fab")
		)
		(fp_line
			(start 0.12065 -0.2794)
			(end 0.12065 -0.3048)
			(stroke
				(width 0.1)
				(type default)
			)
			(layer "F.Fab")
		)
		(fp_line
			(start 0.12065 -0.3048)
			(end 0.67945 -0.3048)
			(stroke
				(width 0.1)
				(type default)
			)
			(layer "F.Fab")
		)
		(fp_line
			(start 0.120396 0.3048)
			(end 0.120396 0.2794)
			(stroke
				(width 0.1)
				(type default)
			)
			(layer "F.Fab")
		)
		(fp_line
			(start 0.120396 0.2794)
			(end -0.12065 0.2794)
			(stroke
				(width 0.1)
				(type default)
			)
			(layer "F.Fab")
		)
		(fp_line
			(start -0.12065 0.3048)
			(end -0.67945 0.3048)
			(stroke
				(width 0.1)
				(type default)
			)
			(layer "F.Fab")
		)
		(fp_line
			(start -0.12065 0.2794)
			(end -0.12065 0.3048)
			(stroke
				(width 0.1)
				(type default)
			)
			(layer "F.Fab")
		)
		(fp_line
			(start -0.12065 -0.2794)
			(end 0.12065 -0.2794)
			(stroke
				(width 0.1)
				(type default)
			)
			(layer "F.Fab")
		)
		(fp_line
			(start -0.12065 -0.305054)
			(end -0.12065 -0.2794)
			(stroke
				(width 0.1)
				(type default)
			)
			(layer "F.Fab")
		)
		(fp_line
			(start -0.67945 0.3048)
			(end -0.67945 -0.305054)
			(stroke
				(width 0.1)
				(type default)
			)
			(layer "F.Fab")
		)
		(fp_line
			(start -0.67945 -0.305054)
			(end -0.12065 -0.305054)
			(stroke
				(width 0.1)
				(type default)
			)
			(layer "F.Fab")
		)
		(pad "1" smd circle
			(at -0.40005 0 180)
			(size 0 0)
			(layers "F.Cu" "F.Mask" "F.Paste")
			(net "SMB_BIC_I2C6_MUX_SSD_8_15_ADC_R_SDA")
		)
		(pad "2" smd circle
			(at 0.40005 0 180)
			(size 0 0)
			(layers "F.Cu" "F.Mask" "F.Paste")
			(net "SMB_SSD15_ADC_SDA")
		)
	)
	(footprint ""
		(layer "F.Cu")
		(at 160.047178 -55.63489 90)
		(property "Reference" "PC371"
			(at 0 0 90)
			(layer "F.SilkS")
			(hide yes)
			(effects
				(font
					(size 1.27 1.27)
				)
			)
		)
		(property "Value" ""
			(at 0 0 90)
			(layer "F.Fab")
			(effects
				(font
					(size 1.27 1.27)
				)
			)
		)
		(duplicate_pad_numbers_are_jumpers no)
		(fp_line
			(start 1.524 -0.762)
			(end 1.524 0.762)
			(stroke
				(width 0.1524)
				(type default)
			)
			(layer "F.SilkS")
		)
		(fp_line
			(start -1.524 -0.762)
			(end 1.524 -0.762)
			(stroke
				(width 0.1524)
				(type default)
			)
			(layer "F.SilkS")
		)
		(fp_line
			(start 1.524 0.762)
			(end -1.524 0.762)
			(stroke
				(width 0.1524)
				(type default)
			)
			(layer "F.SilkS")
		)
		(fp_line
			(start -1.524 0.762)
			(end -1.524 -0.762)
			(stroke
				(width 0.1524)
				(type default)
			)
			(layer "F.SilkS")
		)
		(fp_line
			(start 1.1049 -0.724916)
			(end -1.1049 -0.724916)
			(stroke
				(width 0.1)
				(type default)
			)
			(layer "F.Fab")
		)
		(fp_line
			(start -1.1049 -0.724916)
			(end -1.1049 0.724916)
			(stroke
				(width 0.1)
				(type default)
			)
			(layer "F.Fab")
		)
		(fp_line
			(start 1.1049 0.724916)
			(end 1.1049 -0.724916)
			(stroke
				(width 0.1)
				(type default)
			)
			(layer "F.Fab")
		)
		(fp_line
			(start -1.1049 0.724916)
			(end 1.1049 0.724916)
			(stroke
				(width 0.1)
				(type default)
			)
			(layer "F.Fab")
		)
		(pad "1" smd rect
			(at -0.889 0 270)
			(size 1.016 1.27)
			(layers "F.Cu" "F.Mask" "F.Paste")
			(net "P12V_SSD5_R")
		)
		(pad "2" smd rect
			(at 0.889 0 270)
			(size 1.016 1.27)
			(layers "F.Cu" "F.Mask" "F.Paste")
			(net "GND")
		)
	)
	(footprint ""
		(layer "F.Cu")
		(at 340.458044 -343.952322 90)
		(property "Reference" "C523"
			(at 0 0 90)
			(layer "F.SilkS")
			(hide yes)
			(effects
				(font
					(size 1.27 1.27)
				)
			)
		)
		(property "Value" ""
			(at 0 0 90)
			(layer "F.Fab")
			(effects
				(font
					(size 1.27 1.27)
				)
			)
		)
		(duplicate_pad_numbers_are_jumpers no)
		(fp_line
			(start 0.299974 -0.150114)
			(end 0.299974 0.150114)
			(stroke
				(width 0.1)
				(type default)
			)
			(layer "F.Fab")
		)
		(fp_line
			(start -0.299974 -0.150114)
			(end 0.299974 -0.150114)
			(stroke
				(width 0.1)
				(type default)
			)
			(layer "F.Fab")
		)
		(fp_line
			(start 0.299974 0.150114)
			(end -0.299974 0.150114)
			(stroke
				(width 0.1)
				(type default)
			)
			(layer "F.Fab")
		)
		(fp_line
			(start -0.299974 0.150114)
			(end -0.299974 -0.150114)
			(stroke
				(width 0.1)
				(type default)
			)
			(layer "F.Fab")
		)
		(pad "1" smd rect
			(at -0.2667 0 90)
			(size 0.3048 0.381)
			(layers "F.Cu" "F.Mask" "F.Paste")
			(net "P5E_PEX2_STN5_TX_DP<93>")
		)
		(pad "2" smd rect
			(at 0.2667 0 90)
			(size 0.3048 0.381)
			(layers "F.Cu" "F.Mask" "F.Paste")
			(net "P5E_PEX2_STN5_TX_C_DP<93>")
		)
	)
	(footprint ""
		(layer "F.Cu")
		(at 338.83854 -80.607662 90)
		(property "Reference" "R1174"
			(at 0 0 90)
			(layer "F.SilkS")
			(hide yes)
			(effects
				(font
					(size 1.27 1.27)
				)
			)
		)
		(property "Value" ""
			(at 0 0 90)
			(layer "F.Fab")
			(effects
				(font
					(size 1.27 1.27)
				)
			)
		)
		(duplicate_pad_numbers_are_jumpers no)
		(fp_line
			(start -0.7874 -0.4064)
			(end 0.7874 -0.4064)
			(stroke
				(width 0.1524)
				(type default)
			)
			(layer "F.SilkS")
		)
		(fp_line
			(start -0.12065 -0.305054)
			(end -0.12065 -0.2794)
			(stroke
				(width 0.1)
				(type default)
			)
			(layer "F.Fab")
		)
		(fp_line
			(start -0.67945 -0.305054)
			(end -0.12065 -0.305054)
			(stroke
				(width 0.1)
				(type default)
			)
			(layer "F.Fab")
		)
		(fp_line
			(start 0.67945 -0.3048)
			(end 0.67945 0.3048)
			(stroke
				(width 0.1)
				(type default)
			)
			(layer "F.Fab")
		)
		(fp_line
			(start 0.12065 -0.3048)
			(end 0.67945 -0.3048)
			(stroke
				(width 0.1)
				(type default)
			)
			(layer "F.Fab")
		)
		(fp_line
			(start 0.12065 -0.2794)
			(end 0.12065 -0.3048)
			(stroke
				(width 0.1)
				(type default)
			)
			(layer "F.Fab")
		)
		(fp_line
			(start -0.12065 -0.2794)
			(end 0.12065 -0.2794)
			(stroke
				(width 0.1)
				(type default)
			)
			(layer "F.Fab")
		)
		(fp_line
			(start 0.120396 0.2794)
			(end -0.12065 0.2794)
			(stroke
				(width 0.1)
				(type default)
			)
			(layer "F.Fab")
		)
		(fp_line
			(start -0.12065 0.2794)
			(end -0.12065 0.3048)
			(stroke
				(width 0.1)
				(type default)
			)
			(layer "F.Fab")
		)
		(fp_line
			(start 0.67945 0.3048)
			(end 0.120396 0.3048)
			(stroke
				(width 0.1)
				(type default)
			)
			(layer "F.Fab")
		)
		(fp_line
			(start 0.120396 0.3048)
			(end 0.120396 0.2794)
			(stroke
				(width 0.1)
				(type default)
			)
			(layer "F.Fab")
		)
		(fp_line
			(start -0.12065 0.3048)
			(end -0.67945 0.3048)
			(stroke
				(width 0.1)
				(type default)
			)
			(layer "F.Fab")
		)
		(fp_line
			(start -0.67945 0.3048)
			(end -0.67945 -0.305054)
			(stroke
				(width 0.1)
				(type default)
			)
			(layer "F.Fab")
		)
		(pad "1" smd circle
			(at -0.40005 0 90)
			(size 0 0)
			(layers "F.Cu" "F.Mask" "F.Paste")
			(net "CLK_100M_DB800ZL_SSD10_R_DP")
		)
		(pad "2" smd circle
			(at 0.40005 0 90)
			(size 0 0)
			(layers "F.Cu" "F.Mask" "F.Paste")
			(net "CLK_100M_DB800ZL_SSD10_DP")
		)
	)
	(footprint ""
		(layer "F.Cu")
		(at 336.042 -185.039 180)
		(property "Reference" "R4745"
			(at 0 0 180)
			(layer "F.SilkS")
			(hide yes)
			(effects
				(font
					(size 1.27 1.27)
				)
			)
		)
		(property "Value" ""
			(at 0 0 180)
			(layer "F.Fab")
			(effects
				(font
					(size 1.27 1.27)
				)
			)
		)
		(duplicate_pad_numbers_are_jumpers no)
		(fp_line
			(start 0.7874 0.4064)
			(end -0.7874 0.4064)
			(stroke
				(width 0.1524)
				(type default)
			)
			(layer "F.SilkS")
		)
		(fp_line
			(start 0.7874 -0.4064)
			(end 0.7874 0.4064)
			(stroke
				(width 0.1524)
				(type default)
			)
			(layer "F.SilkS")
		)
		(fp_line
			(start -0.7874 0.4064)
			(end -0.7874 -0.4064)
			(stroke
				(width 0.1524)
				(type default)
			)
			(layer "F.SilkS")
		)
		(fp_line
			(start -0.7874 -0.4064)
			(end 0.7874 -0.4064)
			(stroke
				(width 0.1524)
				(type default)
			)
			(layer "F.SilkS")
		)
		(fp_line
			(start 0.67945 0.3048)
			(end 0.120396 0.3048)
			(stroke
				(width 0.1)
				(type default)
			)
			(layer "F.Fab")
		)
		(fp_line
			(start 0.67945 -0.3048)
			(end 0.67945 0.3048)
			(stroke
				(width 0.1)
				(type default)
			)
			(layer "F.Fab")
		)
		(fp_line
			(start 0.12065 -0.2794)
			(end 0.12065 -0.3048)
			(stroke
				(width 0.1)
				(type default)
			)
			(layer "F.Fab")
		)
		(fp_line
			(start 0.12065 -0.3048)
			(end 0.67945 -0.3048)
			(stroke
				(width 0.1)
				(type default)
			)
			(layer "F.Fab")
		)
		(fp_line
			(start 0.120396 0.3048)
			(end 0.120396 0.2794)
			(stroke
				(width 0.1)
				(type default)
			)
			(layer "F.Fab")
		)
		(fp_line
			(start 0.120396 0.2794)
			(end -0.12065 0.2794)
			(stroke
				(width 0.1)
				(type default)
			)
			(layer "F.Fab")
		)
		(fp_line
			(start -0.12065 0.3048)
			(end -0.67945 0.3048)
			(stroke
				(width 0.1)
				(type default)
			)
			(layer "F.Fab")
		)
		(fp_line
			(start -0.12065 0.2794)
			(end -0.12065 0.3048)
			(stroke
				(width 0.1)
				(type default)
			)
			(layer "F.Fab")
		)
		(fp_line
			(start -0.12065 -0.2794)
			(end 0.12065 -0.2794)
			(stroke
				(width 0.1)
				(type default)
			)
			(layer "F.Fab")
		)
		(fp_line
			(start -0.12065 -0.305054)
			(end -0.12065 -0.2794)
			(stroke
				(width 0.1)
				(type default)
			)
			(layer "F.Fab")
		)
		(fp_line
			(start -0.67945 0.3048)
			(end -0.67945 -0.305054)
			(stroke
				(width 0.1)
				(type default)
			)
			(layer "F.Fab")
		)
		(fp_line
			(start -0.67945 -0.305054)
			(end -0.12065 -0.305054)
			(stroke
				(width 0.1)
				(type default)
			)
			(layer "F.Fab")
		)
		(pad "1" smd circle
			(at -0.40005 0 180)
			(size 0 0)
			(layers "F.Cu" "F.Mask" "F.Paste")
			(net "PCA9555_0_PEX2_A1")
		)
		(pad "2" smd circle
			(at 0.40005 0 180)
			(size 0 0)
			(layers "F.Cu" "F.Mask" "F.Paste")
			(net "P3V3_AUX")
		)
	)
	(footprint ""
		(layer "F.Cu")
		(at 166.330884 -197.900798)
		(property "Reference" "R3407"
			(at 0 0 0)
			(layer "F.SilkS")
			(hide yes)
			(effects
				(font
					(size 1.27 1.27)
				)
			)
		)
		(property "Value" ""
			(at 0 0 0)
			(layer "F.Fab")
			(effects
				(font
					(size 1.27 1.27)
				)
			)
		)
		(duplicate_pad_numbers_are_jumpers no)
		(fp_line
			(start -0.7874 -0.4064)
			(end 0.7874 -0.4064)
			(stroke
				(width 0.1524)
				(type default)
			)
			(layer "F.SilkS")
		)
		(fp_line
			(start -0.7874 0.4064)
			(end -0.7874 -0.4064)
			(stroke
				(width 0.1524)
				(type default)
			)
			(layer "F.SilkS")
		)
		(fp_line
			(start 0.7874 -0.4064)
			(end 0.7874 0.4064)
			(stroke
				(width 0.1524)
				(type default)
			)
			(layer "F.SilkS")
		)
		(fp_line
			(start 0.7874 0.4064)
			(end -0.7874 0.4064)
			(stroke
				(width 0.1524)
				(type default)
			)
			(layer "F.SilkS")
		)
		(fp_line
			(start -0.67945 -0.305054)
			(end -0.12065 -0.305054)
			(stroke
				(width 0.1)
				(type default)
			)
			(layer "F.Fab")
		)
		(fp_line
			(start -0.67945 0.3048)
			(end -0.67945 -0.305054)
			(stroke
				(width 0.1)
				(type default)
			)
			(layer "F.Fab")
		)
		(fp_line
			(start -0.12065 -0.305054)
			(end -0.12065 -0.2794)
			(stroke
				(width 0.1)
				(type default)
			)
			(layer "F.Fab")
		)
		(fp_line
			(start -0.12065 -0.2794)
			(end 0.12065 -0.2794)
			(stroke
				(width 0.1)
				(type default)
			)
			(layer "F.Fab")
		)
		(fp_line
			(start -0.12065 0.2794)
			(end -0.12065 0.3048)
			(stroke
				(width 0.1)
				(type default)
			)
			(layer "F.Fab")
		)
		(fp_line
			(start -0.12065 0.3048)
			(end -0.67945 0.3048)
			(stroke
				(width 0.1)
				(type default)
			)
			(layer "F.Fab")
		)
		(fp_line
			(start 0.120396 0.2794)
			(end -0.12065 0.2794)
			(stroke
				(width 0.1)
				(type default)
			)
			(layer "F.Fab")
		)
		(fp_line
			(start 0.120396 0.3048)
			(end 0.120396 0.2794)
			(stroke
				(width 0.1)
				(type default)
			)
			(layer "F.Fab")
		)
		(fp_line
			(start 0.12065 -0.3048)
			(end 0.67945 -0.3048)
			(stroke
				(width 0.1)
				(type default)
			)
			(layer "F.Fab")
		)
		(fp_line
			(start 0.12065 -0.2794)
			(end 0.12065 -0.3048)
			(stroke
				(width 0.1)
				(type default)
			)
			(layer "F.Fab")
		)
		(fp_line
			(start 0.67945 -0.3048)
			(end 0.67945 0.3048)
			(stroke
				(width 0.1)
				(type default)
			)
			(layer "F.Fab")
		)
		(fp_line
			(start 0.67945 0.3048)
			(end 0.120396 0.3048)
			(stroke
				(width 0.1)
				(type default)
			)
			(layer "F.Fab")
		)
		(pad "1" smd circle
			(at -0.40005 0)
			(size 0 0)
			(layers "F.Cu" "F.Mask" "F.Paste")
			(net "SPI_BIC1_CLK_LS01_R2")
		)
		(pad "2" smd circle
			(at 0.40005 0)
			(size 0 0)
			(layers "F.Cu" "F.Mask" "F.Paste")
			(net "SPI_BIC1_CLK_LS01_R")
		)
	)
)
